FILE_TYPE = MACRO_DRAWING;
SET COLOR_WIRE YELLOW;
SET COLOR_PROP MONO;
SET COLOR_DOT WHITE;
SET COLOR_ARC YELLOW;
SET COLOR_BODY GREEN;
SET COLOR_NOTE MONO;
SET PROP_DISPLAY VALUE;
SET PAGE_NUMBER P126;
FORCEADD OFFPAGE..5
(-7350 4025);
FORCEPROP 2 LAST $XR1 134 
J 0
(-7725 4025);
DISPLAY 0.638298 (-7725 4025);
PAINT MONO (-7725 4025);
FORCEPROP 2 LAST $XR0 119 
J 0
(-7605 4025);
DISPLAY 0.638298 (-7605 4025);
PAINT MONO (-7605 4025);
FORCEPROP 2 LAST BOM_COST SB
J 0
(-7625 4075);
DISPLAY 1.361702 (-7625 4075);
PAINT ORANGE (-7625 4075);
DISPLAY INVISIBLE (-7625 4075);
FORCEPROP 2 LAST ROOM SB
J 0
(-7625 4075);
DISPLAY 1.361702 (-7625 4075);
PAINT ORANGE (-7625 4075);
DISPLAY INVISIBLE (-7625 4075);
FORCEPROP 2 LAST PATH I11
J 0
(-7300 4100);
DISPLAY 1.021277 (-7300 4100);
PAINT ORANGE (-7300 4100);
DISPLAY INVISIBLE (-7300 4100);
FORCEPROP 1 LAST COMMENT_BODY TRUE
J 0
(-7250 3950);
DISPLAY 1.170213 (-7250 3950);
PAINT GREEN (-7250 3950);
DISPLAY INVISIBLE (-7250 3950);
FORCEPROP 2 LAST CDS_LIB mstr_standard
J 0
(-7350 4025);
PAINT ORANGE (-7350 4025);
DISPLAY INVISIBLE (-7350 4025);
FORCEPROP 1 LAST OFFPAGE TRUE
J 0
(-7025 3900);
DISPLAY 1.170213 (-7025 3900);
PAINT GREEN (-7025 3900);
DISPLAY INVISIBLE (-7025 3900);
FORCEADD RES..2
(-6200 2775);
FORCEPROP 1 LAST MATERIAL CHIP
J 0
(-6160 2700);
DISPLAY 0.617021 (-6160 2700);
PAINT SKYBLUE (-6160 2700);
FORCEPROP 1 LAST LOCATION R1D35
J 0
(-6155 2900);
DISPLAY 0.617021 (-6155 2900);
PAINT AQUA (-6155 2900);
FORCEPROP 1 LAST VALUE 4.75K
J 0
(-6155 2850);
DISPLAY 0.617021 (-6155 2850);
PAINT SKYBLUE (-6155 2850);
FORCEPROP 1 LAST WATTAGE 1/16W
J 0
(-6160 2750);
DISPLAY 0.617021 (-6160 2750);
PAINT SKYBLUE (-6160 2750);
FORCEPROP 1 LAST PART_NUMBER G21796-072
J 0
(-6160 2650);
DISPLAY 0.617021 (-6160 2650);
PAINT BLUE (-6160 2650);
FORCEPROP 1 LAST TOLERANCE 1%
J 0
(-6155 2800);
DISPLAY 0.617021 (-6155 2800);
PAINT SKYBLUE (-6155 2800);
FORCEPROP 1 LAST PACK_TYPE 0402
J 0
(-6160 2600);
DISPLAY 0.617021 (-6160 2600);
PAINT SKYBLUE (-6160 2600);
FORCEPROP 1 LASTPIN (-6200 2675) $PN 2
J 0
(-6195 2685);
DISPLAY 0.617021 (-6195 2685);
PAINT ORANGE (-6195 2685);
FORCEPROP 1 LASTPIN (-6200 2875) $PN 1
J 0
(-6195 2837);
DISPLAY 0.617021 (-6195 2837);
PAINT ORANGE (-6195 2837);
FORCEPROP 2 LAST ROOM BMC_MISC
J 0
(-6250 2875);
DISPLAY 1.021277 (-6250 2875);
PAINT ORANGE (-6250 2875);
DISPLAY INVISIBLE (-6250 2875);
FORCEPROP 2 LAST CDS_LIB mstr_discrete
J 0
(-6200 2775);
PAINT ORANGE (-6200 2775);
DISPLAY INVISIBLE (-6200 2775);
FORCEPROP 2 LAST CDS_LOCATION R1D35
J 0
(-6155 2900);
DISPLAY 0.617021 (-6155 2900);
PAINT AQUA (-6155 2900);
DISPLAY INVISIBLE (-6155 2900);
FORCEPROP 2 LAST BOM_COST SM_CONTROLLER
J 0
(-6250 2925);
DISPLAY 1.021277 (-6250 2925);
PAINT ORANGE (-6250 2925);
DISPLAY INVISIBLE (-6250 2925);
FORCEPROP 2 LAST SEC_TYPE 0402
J 0
(-6150 3000);
DISPLAY 1.021277 (-6150 3000);
PAINT ORANGE (-6150 3000);
DISPLAY INVISIBLE (-6150 3000);
FORCEPROP 2 LAST SEC 1
J 0
(-6150 3000);
DISPLAY 0.680851 (-6150 3000);
PAINT MONO (-6150 3000);
DISPLAY INVISIBLE (-6150 3000);
FORCEPROP 1 LAST PATH I12
J 0
(-6150 2950);
DISPLAY 0.978723 (-6150 2950);
PAINT WHITE (-6150 2950);
DISPLAY INVISIBLE (-6150 2950);
FORCEADD FET_N..8
(-3625 3925);
FORCEPROP 1 LAST LOCATION Q8E2
J 0
(-3425 3925);
DISPLAY 0.617021 (-3425 3925);
PAINT AQUA (-3425 3925);
FORCEPROP 1 LAST PART_NUMBER C79254-001
J 0
(-3425 3725);
DISPLAY 0.617021 (-3425 3725);
PAINT BLUE (-3425 3725);
FORCEPROP 1 LAST VALUE 2N7002
J 0
(-3425 3875);
DISPLAY 0.617021 (-3425 3875);
PAINT SKYBLUE (-3425 3875);
FORCEPROP 1 LAST MATERIAL FET
J 0
(-3425 3825);
DISPLAY 0.617021 (-3425 3825);
PAINT SKYBLUE (-3425 3825);
FORCEPROP 1 LASTPIN (-3825 3825) $PN 1
J 2
(-3822 3840);
DISPLAY 0.617021 (-3822 3840);
PAINT WHITE (-3822 3840);
FORCEPROP 1 LASTPIN (-3625 3725) $PN 2
J 2
(-3567 3725);
DISPLAY 0.617021 (-3567 3725);
PAINT WHITE (-3567 3725);
FORCEPROP 1 LASTPIN (-3625 4125) $PN 3
J 2
(-3572 4090);
DISPLAY 0.617021 (-3572 4090);
PAINT WHITE (-3572 4090);
FORCEPROP 1 LAST PACK_TYPE SOT23LF
J 0
(-3425 3775);
DISPLAY 0.978723 (-3425 3775);
PAINT SKYBLUE (-3425 3775);
DISPLAY INVISIBLE (-3425 3775);
FORCEPROP 2 LAST CDS_LIB mstr_discrete
J 0
(-3625 3925);
PAINT ORANGE (-3625 3925);
DISPLAY INVISIBLE (-3625 3925);
FORCEPROP 1 LAST PATH I13
J 0
(-3425 3975);
DISPLAY 0.978723 (-3425 3975);
PAINT BLUE (-3425 3975);
DISPLAY INVISIBLE (-3425 3975);
FORCEPROP 2 LAST SEC 1
J 0
(-3425 4025);
DISPLAY 0.680851 (-3425 4025);
PAINT MONO (-3425 4025);
DISPLAY INVISIBLE (-3425 4025);
FORCEPROP 2 LAST SEC_TYPE SOT23LF
J 0
(-3425 4025);
DISPLAY 1.021277 (-3425 4025);
PAINT ORANGE (-3425 4025);
DISPLAY INVISIBLE (-3425 4025);
FORCEADD GND..1
(-3625 3575);
FORCEPROP 3 LASTPIN (-3625 3625) SIG_NAME GND\g
J 0
(-3615 3635);
DISPLAY 0.659574 (-3615 3635);
PAINT MONO (-3615 3635);
DISPLAY INVISIBLE (-3615 3635);
FORCEPROP 1 LAST VOLTAGE 0.0V
J 0
(-3670 3532);
DISPLAY 0.340426 (-3670 3532);
PAINT SKYBLUE (-3670 3532);
DISPLAY INVISIBLE (-3670 3532);
FORCEPROP 1 LAST HDL_POWER GND
J 0
(-3625 3725);
DISPLAY 1.170213 (-3625 3725);
PAINT GREEN (-3625 3725);
DISPLAY INVISIBLE (-3625 3725);
FORCEPROP 2 LAST ROOM SB
J 0
(-3600 3650);
DISPLAY 1.361702 (-3600 3650);
PAINT ORANGE (-3600 3650);
DISPLAY INVISIBLE (-3600 3650);
FORCEPROP 1 LAST BODY_TYPE PLUMBING
J 0
(-3670 3532);
DISPLAY 0.340426 (-3670 3532);
PAINT GREEN (-3670 3532);
DISPLAY INVISIBLE (-3670 3532);
FORCEPROP 2 LAST CDS_LIB mstr_symbols
J 0
(-3625 3575);
PAINT ORANGE (-3625 3575);
DISPLAY INVISIBLE (-3625 3575);
FORCEPROP 2 LAST BOM_COST SB
J 0
(-3600 3650);
DISPLAY 1.361702 (-3600 3650);
PAINT ORANGE (-3600 3650);
DISPLAY INVISIBLE (-3600 3650);
FORCEPROP 1 LAST SIZE 1B
J 0
(-3550 3525);
DISPLAY 1.170213 (-3550 3525);
PAINT AQUA (-3550 3525);
DISPLAY INVISIBLE (-3550 3525);
FORCEPROP 1 LAST PATH I14
J 0
(-3550 3575);
DISPLAY 0.872340 (-3550 3575);
PAINT AQUA (-3550 3575);
DISPLAY INVISIBLE (-3550 3575);
FORCEADD P3V3_STBY..1
(-3625 4650);
FORCEPROP 3 LASTPIN (-3625 4600) SIG_NAME P3V3_STBY\g
J 0
(-3615 4610);
DISPLAY 0.659574 (-3615 4610);
PAINT MONO (-3615 4610);
DISPLAY INVISIBLE (-3615 4610);
FORCEPROP 1 LAST VOLTAGE 3.3V
J 0
(-3670 4607);
DISPLAY 0.340426 (-3670 4607);
PAINT SKYBLUE (-3670 4607);
DISPLAY INVISIBLE (-3670 4607);
FORCEPROP 1 LAST HDL_POWER P3V3_STBY
J 0
(-3925 4525);
DISPLAY 0.872340 (-3925 4525);
PAINT ORANGE (-3925 4525);
DISPLAY INVISIBLE (-3925 4525);
FORCEPROP 1 LAST BODY_TYPE PLUMBING
J 0
(-3670 4607);
DISPLAY 0.340426 (-3670 4607);
PAINT GREEN (-3670 4607);
DISPLAY INVISIBLE (-3670 4607);
FORCEPROP 2 LAST CDS_LIB mstr_symbols
J 0
(-3625 4650);
PAINT ORANGE (-3625 4650);
DISPLAY INVISIBLE (-3625 4650);
FORCEPROP 1 LAST SIZE 1B
J 0
(-3580 4672);
DISPLAY 0.340426 (-3580 4672);
PAINT GREEN (-3580 4672);
DISPLAY INVISIBLE (-3580 4672);
FORCEPROP 1 LAST PATH I16
J 0
(-3580 4652);
DISPLAY 0.340426 (-3580 4652);
PAINT GREEN (-3580 4652);
DISPLAY INVISIBLE (-3580 4652);
FORCEADD OFFPAGE..2
(-2900 4225);
FORCEPROP 2 LAST $XR1 146 
J 0
(-2591 4225);
DISPLAY 0.638298 (-2591 4225);
PAINT MONO (-2591 4225);
FORCEPROP 2 LAST $XR0 119 
J 0
(-2711 4225);
DISPLAY 0.638298 (-2711 4225);
PAINT MONO (-2711 4225);
FORCEPROP 1 LAST OFFPAGE TRUE
J 0
(-2575 4100);
PAINT GREEN (-2575 4100);
DISPLAY INVISIBLE (-2575 4100);
FORCEPROP 2 LAST PATH I17
J 0
(-2575 4275);
DISPLAY 1.021277 (-2575 4275);
PAINT ORANGE (-2575 4275);
DISPLAY INVISIBLE (-2575 4275);
FORCEPROP 2 LAST CDS_LIB mstr_standard
J 0
(-2900 4225);
DISPLAY 1.361702 (-2900 4225);
PAINT ORANGE (-2900 4225);
DISPLAY INVISIBLE (-2900 4225);
FORCEPROP 1 LAST COMMENT_BODY TRUE
J 0
(-2945 4130);
DISPLAY 1.170213 (-2945 4130);
PAINT GREEN (-2945 4130);
DISPLAY INVISIBLE (-2945 4130);
FORCEADD RES..2
(-3625 4425);
FORCEPROP 1 LAST LOCATION R8C9
J 0
(-3580 4550);
DISPLAY 0.617021 (-3580 4550);
PAINT AQUA (-3580 4550);
FORCEPROP 1 LAST PART_NUMBER G21796-072
J 0
(-3585 4300);
DISPLAY 0.617021 (-3585 4300);
PAINT BLUE (-3585 4300);
FORCEPROP 1 LAST TOLERANCE 1%
J 0
(-3580 4450);
DISPLAY 0.617021 (-3580 4450);
PAINT SKYBLUE (-3580 4450);
FORCEPROP 1 LAST MATERIAL CHIP
J 0
(-3585 4350);
DISPLAY 0.617021 (-3585 4350);
PAINT SKYBLUE (-3585 4350);
FORCEPROP 1 LAST WATTAGE 1/16W
J 0
(-3585 4400);
DISPLAY 0.617021 (-3585 4400);
PAINT SKYBLUE (-3585 4400);
FORCEPROP 1 LASTPIN (-3625 4325) $PN 2
J 0
(-3620 4335);
DISPLAY 0.617021 (-3620 4335);
PAINT ORANGE (-3620 4335);
FORCEPROP 1 LASTPIN (-3625 4525) $PN 1
J 0
(-3620 4487);
DISPLAY 0.617021 (-3620 4487);
PAINT ORANGE (-3620 4487);
FORCEPROP 1 LAST PACK_TYPE 0402
J 0
(-3585 4250);
DISPLAY 0.617021 (-3585 4250);
PAINT SKYBLUE (-3585 4250);
FORCEPROP 1 LAST VALUE 4.75K
J 0
(-3580 4500);
DISPLAY 0.617021 (-3580 4500);
PAINT SKYBLUE (-3580 4500);
FORCEPROP 2 LAST ROOM BMC_MISC
J 0
(-3675 4525);
DISPLAY 1.021277 (-3675 4525);
PAINT ORANGE (-3675 4525);
DISPLAY INVISIBLE (-3675 4525);
FORCEPROP 2 LAST CDS_LIB mstr_discrete
J 0
(-3625 4425);
PAINT MONO (-3625 4425);
DISPLAY INVISIBLE (-3625 4425);
FORCEPROP 2 LAST BOM_COST SM_CONTROLLER
J 0
(-3675 4575);
DISPLAY 1.021277 (-3675 4575);
PAINT ORANGE (-3675 4575);
DISPLAY INVISIBLE (-3675 4575);
FORCEPROP 2 LAST SEC_TYPE 0402
J 0
(-3575 4650);
DISPLAY 1.021277 (-3575 4650);
PAINT ORANGE (-3575 4650);
DISPLAY INVISIBLE (-3575 4650);
FORCEPROP 2 LAST SEC 1
J 0
(-3575 4650);
DISPLAY 0.680851 (-3575 4650);
PAINT MONO (-3575 4650);
DISPLAY INVISIBLE (-3575 4650);
FORCEPROP 2 LAST CDS_LOCATION R8C9
J 0
(-3580 4550);
DISPLAY 0.617021 (-3580 4550);
PAINT AQUA (-3580 4550);
DISPLAY INVISIBLE (-3580 4550);
FORCEPROP 1 LAST PATH I20
J 0
(-3575 4600);
DISPLAY 0.978723 (-3575 4600);
PAINT WHITE (-3575 4600);
DISPLAY INVISIBLE (-3575 4600);
FORCEADD OFFPAGE..1
(-4475 3825);
FORCEPROP 2 LAST $XR0 190 
J 0
(-4757 3825);
DISPLAY 0.638298 (-4757 3825);
PAINT MONO (-4757 3825);
FORCEPROP 1 LAST OFFPAGE TRUE
J 0
(-4150 3700);
DISPLAY 0.872340 (-4150 3700);
PAINT GREEN (-4150 3700);
DISPLAY INVISIBLE (-4150 3700);
FORCEPROP 1 LAST COMMENT_BODY TRUE
J 0
(-4350 3725);
DISPLAY 0.872340 (-4350 3725);
PAINT GREEN (-4350 3725);
DISPLAY INVISIBLE (-4350 3725);
FORCEPROP 2 LAST CDS_LIB mstr_standard
J 0
(-4475 3825);
PAINT ORANGE (-4475 3825);
DISPLAY INVISIBLE (-4475 3825);
FORCEPROP 2 LAST PATH I21
J 0
(-4425 3900);
DISPLAY 1.021277 (-4425 3900);
PAINT ORANGE (-4425 3900);
DISPLAY INVISIBLE (-4425 3900);
FORCEADD RES..2
(-4525 2725);
FORCEPROP 1 LAST PART_NUMBER G21796-072
J 0
(-4485 2600);
DISPLAY 0.617021 (-4485 2600);
PAINT BLUE (-4485 2600);
FORCEPROP 1 LAST MATERIAL EMPTY
J 0
(-4485 2650);
DISPLAY 0.617021 (-4485 2650);
PAINT RED (-4485 2650);
FORCEPROP 1 LAST WATTAGE 1/16W
J 0
(-4485 2700);
DISPLAY 0.617021 (-4485 2700);
PAINT SKYBLUE (-4485 2700);
FORCEPROP 1 LAST LOCATION R3P62
J 0
(-4480 2850);
DISPLAY 0.617021 (-4480 2850);
PAINT AQUA (-4480 2850);
FORCEPROP 1 LAST VALUE 4.75K
J 0
(-4480 2800);
DISPLAY 0.617021 (-4480 2800);
PAINT SKYBLUE (-4480 2800);
FORCEPROP 1 LAST TOLERANCE 1%
J 0
(-4480 2750);
DISPLAY 0.617021 (-4480 2750);
PAINT SKYBLUE (-4480 2750);
FORCEPROP 1 LAST PACK_TYPE 0402
J 0
(-4485 2550);
DISPLAY 0.617021 (-4485 2550);
PAINT SKYBLUE (-4485 2550);
FORCEPROP 1 LASTPIN (-4525 2625) $PN 2
J 0
(-4520 2635);
DISPLAY 0.617021 (-4520 2635);
PAINT ORANGE (-4520 2635);
FORCEPROP 1 LASTPIN (-4525 2825) $PN 1
J 0
(-4520 2787);
DISPLAY 0.617021 (-4520 2787);
PAINT ORANGE (-4520 2787);
FORCEPROP 2 LAST CDS_LIB mstr_discrete
J 0
(-4525 2725);
PAINT ORANGE (-4525 2725);
DISPLAY INVISIBLE (-4525 2725);
FORCEPROP 1 LAST PATH I22
J 0
(-4475 2900);
DISPLAY 0.978723 (-4475 2900);
PAINT WHITE (-4475 2900);
DISPLAY INVISIBLE (-4475 2900);
FORCEPROP 0 LAST SEC 1
J 0
(-4475 2900);
DISPLAY 0.680851 (-4475 2900);
PAINT MONO (-4475 2900);
DISPLAY INVISIBLE (-4475 2900);
FORCEPROP 2 LAST SEC_TYPE 0402
J 0
(-4475 2950);
DISPLAY 1.021277 (-4475 2950);
PAINT ORANGE (-4475 2950);
DISPLAY INVISIBLE (-4475 2950);
FORCEADD RES..2
(-4525 2275);
FORCEPROP 1 LAST MATERIAL EMPTY
J 0
(-4485 2200);
DISPLAY 0.617021 (-4485 2200);
PAINT RED (-4485 2200);
FORCEPROP 1 LAST LOCATION R3P64
J 0
(-4480 2400);
DISPLAY 0.617021 (-4480 2400);
PAINT AQUA (-4480 2400);
FORCEPROP 1 LAST PART_NUMBER G21796-026
J 0
(-4485 2150);
DISPLAY 0.617021 (-4485 2150);
PAINT BLUE (-4485 2150);
FORCEPROP 1 LAST VALUE 1.00K
J 0
(-4480 2350);
DISPLAY 0.617021 (-4480 2350);
PAINT SKYBLUE (-4480 2350);
FORCEPROP 1 LAST TOLERANCE 1%
J 0
(-4480 2300);
DISPLAY 0.617021 (-4480 2300);
PAINT SKYBLUE (-4480 2300);
FORCEPROP 1 LAST PACK_TYPE 0402
J 0
(-4485 2100);
DISPLAY 0.617021 (-4485 2100);
PAINT SKYBLUE (-4485 2100);
FORCEPROP 1 LAST WATTAGE 1/16W
J 0
(-4485 2250);
DISPLAY 0.617021 (-4485 2250);
PAINT SKYBLUE (-4485 2250);
FORCEPROP 1 LASTPIN (-4525 2175) $PN 2
J 0
(-4520 2185);
DISPLAY 0.617021 (-4520 2185);
PAINT ORANGE (-4520 2185);
FORCEPROP 1 LASTPIN (-4525 2375) $PN 1
J 0
(-4520 2337);
DISPLAY 0.617021 (-4520 2337);
PAINT ORANGE (-4520 2337);
FORCEPROP 2 LAST CDS_LIB mstr_discrete
J 0
(-4525 2275);
PAINT ORANGE (-4525 2275);
DISPLAY INVISIBLE (-4525 2275);
FORCEPROP 2 LAST SEC_TYPE 0402
J 0
(-4475 2500);
DISPLAY 1.021277 (-4475 2500);
PAINT ORANGE (-4475 2500);
DISPLAY INVISIBLE (-4475 2500);
FORCEPROP 0 LAST SEC 1
J 0
(-4475 2450);
DISPLAY 0.680851 (-4475 2450);
PAINT MONO (-4475 2450);
DISPLAY INVISIBLE (-4475 2450);
FORCEPROP 1 LAST PATH I23
J 0
(-4475 2450);
DISPLAY 0.978723 (-4475 2450);
PAINT WHITE (-4475 2450);
DISPLAY INVISIBLE (-4475 2450);
FORCEADD GND..1
(-4525 2050);
FORCEPROP 3 LASTPIN (-4525 2100) SIG_NAME GND\g
J 0
(-4515 2110);
DISPLAY 0.659574 (-4515 2110);
PAINT MONO (-4515 2110);
DISPLAY INVISIBLE (-4515 2110);
FORCEPROP 1 LAST VOLTAGE 0.0V
J 0
(-4570 2007);
DISPLAY 0.340426 (-4570 2007);
PAINT SKYBLUE (-4570 2007);
DISPLAY INVISIBLE (-4570 2007);
FORCEPROP 1 LAST HDL_POWER GND
J 0
(-4525 2200);
DISPLAY 0.872340 (-4525 2200);
PAINT GREEN (-4525 2200);
DISPLAY INVISIBLE (-4525 2200);
FORCEPROP 1 LAST BODY_TYPE PLUMBING
J 0
(-4570 2007);
DISPLAY 0.340426 (-4570 2007);
PAINT GREEN (-4570 2007);
DISPLAY INVISIBLE (-4570 2007);
FORCEPROP 1 LAST SIZE 1B
J 0
(-4450 2000);
DISPLAY 0.872340 (-4450 2000);
PAINT AQUA (-4450 2000);
DISPLAY INVISIBLE (-4450 2000);
FORCEPROP 2 LAST CDS_LIB mstr_symbols
J 0
(-4525 2050);
PAINT ORANGE (-4525 2050);
DISPLAY INVISIBLE (-4525 2050);
FORCEPROP 1 LAST PATH I24
J 0
(-4450 2050);
DISPLAY 0.872340 (-4450 2050);
PAINT AQUA (-4450 2050);
DISPLAY INVISIBLE (-4450 2050);
FORCEADD P3V3_STBY..1
(-4525 2975);
FORCEPROP 3 LASTPIN (-4525 2925) SIG_NAME P3V3_STBY\g
J 0
(-4515 2935);
DISPLAY 0.659574 (-4515 2935);
PAINT MONO (-4515 2935);
DISPLAY INVISIBLE (-4515 2935);
FORCEPROP 1 LAST VOLTAGE 3.3V
J 0
(-4570 2932);
DISPLAY 0.340426 (-4570 2932);
PAINT SKYBLUE (-4570 2932);
DISPLAY INVISIBLE (-4570 2932);
FORCEPROP 1 LAST HDL_POWER P3V3_STBY
J 0
(-4825 2850);
DISPLAY 0.872340 (-4825 2850);
PAINT ORANGE (-4825 2850);
DISPLAY INVISIBLE (-4825 2850);
FORCEPROP 2 LAST CDS_LIB mstr_symbols
J 0
(-4525 2975);
PAINT ORANGE (-4525 2975);
DISPLAY INVISIBLE (-4525 2975);
FORCEPROP 1 LAST BODY_TYPE PLUMBING
J 0
(-4570 2932);
DISPLAY 0.340426 (-4570 2932);
PAINT GREEN (-4570 2932);
DISPLAY INVISIBLE (-4570 2932);
FORCEPROP 1 LAST PATH I25
J 0
(-4480 2977);
DISPLAY 0.340426 (-4480 2977);
PAINT GREEN (-4480 2977);
DISPLAY INVISIBLE (-4480 2977);
FORCEPROP 1 LAST SIZE 1B
J 0
(-4480 2997);
DISPLAY 0.340426 (-4480 2997);
PAINT GREEN (-4480 2997);
DISPLAY INVISIBLE (-4480 2997);
FORCEADD OFFPAGE..2
(-3375 2475);
FORCEPROP 2 LAST $XR0 120 
J 0
(-3186 2475);
DISPLAY 0.638298 (-3186 2475);
PAINT MONO (-3186 2475);
FORCEPROP 1 LAST OFFPAGE TRUE
J 0
(-3050 2350);
DISPLAY 0.872340 (-3050 2350);
PAINT GREEN (-3050 2350);
DISPLAY INVISIBLE (-3050 2350);
FORCEPROP 2 LAST PATH I26
J 0
(-3325 2550);
DISPLAY 1.021277 (-3325 2550);
PAINT ORANGE (-3325 2550);
DISPLAY INVISIBLE (-3325 2550);
FORCEPROP 2 LAST CDS_LIB mstr_standard
J 0
(-3375 2475);
PAINT ORANGE (-3375 2475);
DISPLAY INVISIBLE (-3375 2475);
FORCEPROP 1 LAST COMMENT_BODY TRUE
J 0
(-3420 2380);
DISPLAY 0.872340 (-3420 2380);
PAINT GREEN (-3420 2380);
DISPLAY INVISIBLE (-3420 2380);
FORCEADD RES..2
R 2
(-6325 4300);
FORCEPROP 1 LAST LOCATION R2N10
J 2
(-6370 4425);
DISPLAY 0.617021 (-6370 4425);
PAINT AQUA (-6370 4425);
FORCEPROP 1 LASTPIN (-6325 4400) $PN 1
J 2
(-6330 4362);
DISPLAY 0.617021 (-6330 4362);
PAINT ORANGE (-6330 4362);
FORCEPROP 1 LAST MATERIAL EMPTY
J 2
(-6365 4225);
DISPLAY 0.617021 (-6365 4225);
PAINT RED (-6365 4225);
FORCEPROP 1 LAST PART_NUMBER G21796-072
J 2
(-6365 4175);
DISPLAY 0.617021 (-6365 4175);
PAINT BLUE (-6365 4175);
FORCEPROP 1 LAST PACK_TYPE 0402
J 2
(-6365 4125);
DISPLAY 0.617021 (-6365 4125);
PAINT SKYBLUE (-6365 4125);
FORCEPROP 1 LASTPIN (-6325 4200) $PN 2
J 2
(-6330 4210);
DISPLAY 0.617021 (-6330 4210);
PAINT ORANGE (-6330 4210);
FORCEPROP 1 LAST WATTAGE 1/16W
J 2
(-6365 4275);
DISPLAY 0.617021 (-6365 4275);
PAINT SKYBLUE (-6365 4275);
FORCEPROP 1 LAST TOLERANCE 1%
J 2
(-6370 4325);
DISPLAY 0.617021 (-6370 4325);
PAINT SKYBLUE (-6370 4325);
FORCEPROP 1 LAST VALUE 4.75K
J 2
(-6370 4375);
DISPLAY 0.617021 (-6370 4375);
PAINT SKYBLUE (-6370 4375);
FORCEPROP 2 LAST SEC_TYPE 0402
J 0
(-6375 4525);
DISPLAY 1.021277 (-6375 4525);
PAINT ORANGE (-6375 4525);
DISPLAY INVISIBLE (-6375 4525);
FORCEPROP 2 LAST BOM_COST SYS_CLOCK
J 2
(-6375 4625);
DISPLAY 1.021277 (-6375 4625);
PAINT ORANGE (-6375 4625);
DISPLAY INVISIBLE (-6375 4625);
FORCEPROP 2 LAST SEC 1
J 0
(-6375 4525);
DISPLAY 0.680851 (-6375 4525);
PAINT MONO (-6375 4525);
DISPLAY INVISIBLE (-6375 4525);
FORCEPROP 2 LAST ROOM DB1200ZL
J 2
(-6375 4525);
DISPLAY 1.021277 (-6375 4525);
PAINT ORANGE (-6375 4525);
DISPLAY INVISIBLE (-6375 4525);
FORCEPROP 2 LAST CDS_LIB mstr_discrete
J 0
(-6325 4300);
PAINT MONO (-6325 4300);
DISPLAY INVISIBLE (-6325 4300);
FORCEPROP 1 LAST PATH I27
J 2
(-6375 4475);
DISPLAY 0.978723 (-6375 4475);
PAINT WHITE (-6375 4475);
DISPLAY INVISIBLE (-6375 4475);
FORCEPROP 2 LAST CDS_LOCATION R2N10
J 2
(-6370 4425);
DISPLAY 0.617021 (-6370 4425);
PAINT AQUA (-6370 4425);
DISPLAY INVISIBLE (-6370 4425);
FORCEADD GND..1
(-6200 2100);
FORCEPROP 3 LASTPIN (-6200 2150) SIG_NAME GND\g
J 0
(-6190 2160);
DISPLAY 0.659574 (-6190 2160);
PAINT MONO (-6190 2160);
DISPLAY INVISIBLE (-6190 2160);
FORCEPROP 1 LAST VOLTAGE 0.0V
J 0
(-6245 2057);
DISPLAY 0.340426 (-6245 2057);
PAINT SKYBLUE (-6245 2057);
DISPLAY INVISIBLE (-6245 2057);
FORCEPROP 1 LAST HDL_POWER GND
J 0
(-6200 2250);
DISPLAY 1.170213 (-6200 2250);
PAINT GREEN (-6200 2250);
DISPLAY INVISIBLE (-6200 2250);
FORCEPROP 2 LAST ROOM SB
J 0
(-6175 2175);
DISPLAY 1.361702 (-6175 2175);
PAINT ORANGE (-6175 2175);
DISPLAY INVISIBLE (-6175 2175);
FORCEPROP 2 LAST CDS_LIB mstr_symbols
J 0
(-6200 2100);
PAINT ORANGE (-6200 2100);
DISPLAY INVISIBLE (-6200 2100);
FORCEPROP 1 LAST BODY_TYPE PLUMBING
J 0
(-6245 2057);
DISPLAY 0.340426 (-6245 2057);
PAINT GREEN (-6245 2057);
DISPLAY INVISIBLE (-6245 2057);
FORCEPROP 2 LAST BOM_COST SB
J 0
(-6175 2175);
DISPLAY 1.361702 (-6175 2175);
PAINT ORANGE (-6175 2175);
DISPLAY INVISIBLE (-6175 2175);
FORCEPROP 1 LAST SIZE 1B
J 0
(-6125 2050);
DISPLAY 1.170213 (-6125 2050);
PAINT AQUA (-6125 2050);
DISPLAY INVISIBLE (-6125 2050);
FORCEPROP 1 LAST PATH I5
J 0
(-6125 2100);
DISPLAY 0.872340 (-6125 2100);
PAINT AQUA (-6125 2100);
DISPLAY INVISIBLE (-6125 2100);
FORCEADD RES..2
(-6200 2350);
FORCEPROP 1 LAST PART_NUMBER G21796-026
J 0
(-6160 2225);
DISPLAY 0.617021 (-6160 2225);
PAINT BLUE (-6160 2225);
FORCEPROP 1 LAST MATERIAL EMPTY
J 0
(-6160 2275);
DISPLAY 0.617021 (-6160 2275);
PAINT RED (-6160 2275);
FORCEPROP 1 LAST LOCATION R7D19
J 0
(-6155 2475);
DISPLAY 0.617021 (-6155 2475);
PAINT AQUA (-6155 2475);
FORCEPROP 1 LAST VALUE 1.00K
J 0
(-6155 2425);
DISPLAY 0.617021 (-6155 2425);
PAINT SKYBLUE (-6155 2425);
FORCEPROP 1 LAST TOLERANCE 1%
J 0
(-6155 2375);
DISPLAY 0.617021 (-6155 2375);
PAINT SKYBLUE (-6155 2375);
FORCEPROP 1 LAST PACK_TYPE 0402
J 0
(-6160 2175);
DISPLAY 0.617021 (-6160 2175);
PAINT SKYBLUE (-6160 2175);
FORCEPROP 1 LAST WATTAGE 1/16W
J 0
(-6160 2325);
DISPLAY 0.617021 (-6160 2325);
PAINT SKYBLUE (-6160 2325);
FORCEPROP 1 LASTPIN (-6200 2250) $PN 2
J 0
(-6195 2260);
DISPLAY 0.617021 (-6195 2260);
PAINT ORANGE (-6195 2260);
FORCEPROP 1 LASTPIN (-6200 2450) $PN 1
J 0
(-6195 2412);
DISPLAY 0.617021 (-6195 2412);
PAINT ORANGE (-6195 2412);
FORCEPROP 2 LAST ROOM SB
J 0
(-6150 2525);
DISPLAY 1.361702 (-6150 2525);
PAINT ORANGE (-6150 2525);
DISPLAY INVISIBLE (-6150 2525);
FORCEPROP 2 LAST CDS_LIB mstr_discrete
J 0
(-6200 2350);
PAINT ORANGE (-6200 2350);
DISPLAY INVISIBLE (-6200 2350);
FORCEPROP 2 LAST CDS_LOCATION R7D19
J 0
(-6155 2475);
DISPLAY 0.617021 (-6155 2475);
PAINT AQUA (-6155 2475);
DISPLAY INVISIBLE (-6155 2475);
FORCEPROP 2 LAST BOM_COST SB
J 0
(-6150 2525);
DISPLAY 1.361702 (-6150 2525);
PAINT ORANGE (-6150 2525);
DISPLAY INVISIBLE (-6150 2525);
FORCEPROP 1 LAST PATH I6
J 0
(-6150 2525);
DISPLAY 0.978723 (-6150 2525);
PAINT WHITE (-6150 2525);
DISPLAY INVISIBLE (-6150 2525);
FORCEPROP 2 LAST SEC_TYPE 0402
J 0
(-6150 2575);
DISPLAY 1.021277 (-6150 2575);
PAINT ORANGE (-6150 2575);
DISPLAY INVISIBLE (-6150 2575);
FORCEPROP 2 LAST SEC 1
J 0
(-6150 2575);
DISPLAY 0.680851 (-6150 2575);
PAINT MONO (-6150 2575);
DISPLAY INVISIBLE (-6150 2575);
FORCEADD P3V3_STBY..1
(-6200 3000);
FORCEPROP 3 LASTPIN (-6200 2950) SIG_NAME P3V3_STBY\g
J 0
(-6190 2960);
DISPLAY 0.659574 (-6190 2960);
PAINT MONO (-6190 2960);
DISPLAY INVISIBLE (-6190 2960);
FORCEPROP 1 LAST VOLTAGE 3.3V
J 0
(-6245 2957);
DISPLAY 0.340426 (-6245 2957);
PAINT SKYBLUE (-6245 2957);
DISPLAY INVISIBLE (-6245 2957);
FORCEPROP 1 LAST HDL_POWER P3V3_STBY
J 0
(-6500 2875);
DISPLAY 0.872340 (-6500 2875);
PAINT ORANGE (-6500 2875);
DISPLAY INVISIBLE (-6500 2875);
FORCEPROP 1 LAST SIZE 1B
J 0
(-6155 3022);
DISPLAY 0.340426 (-6155 3022);
PAINT GREEN (-6155 3022);
DISPLAY INVISIBLE (-6155 3022);
FORCEPROP 2 LAST CDS_LIB mstr_symbols
J 0
(-6200 3000);
PAINT ORANGE (-6200 3000);
DISPLAY INVISIBLE (-6200 3000);
FORCEPROP 1 LAST BODY_TYPE PLUMBING
J 0
(-6245 2957);
DISPLAY 0.340426 (-6245 2957);
PAINT GREEN (-6245 2957);
DISPLAY INVISIBLE (-6245 2957);
FORCEPROP 1 LAST PATH I7
J 0
(-6155 3002);
DISPLAY 0.340426 (-6155 3002);
PAINT GREEN (-6155 3002);
DISPLAY INVISIBLE (-6155 3002);
FORCEADD OFFPAGE..5
(-7150 2575);
FORCEPROP 2 LAST $XR2 200 
J 0
(-7645 2575);
DISPLAY 0.638298 (-7645 2575);
PAINT MONO (-7645 2575);
FORCEPROP 2 LAST $XR1 145 
J 0
(-7525 2575);
DISPLAY 0.638298 (-7525 2575);
PAINT MONO (-7525 2575);
FORCEPROP 2 LAST $XR0 120 
J 0
(-7405 2575);
DISPLAY 0.638298 (-7405 2575);
PAINT MONO (-7405 2575);
FORCEPROP 2 LAST CDS_LIB mstr_standard
J 0
(-7150 2575);
PAINT ORANGE (-7150 2575);
DISPLAY INVISIBLE (-7150 2575);
FORCEPROP 1 LAST OFFPAGE TRUE
J 0
(-6825 2450);
DISPLAY 1.170213 (-6825 2450);
PAINT GREEN (-6825 2450);
DISPLAY INVISIBLE (-6825 2450);
FORCEPROP 1 LAST COMMENT_BODY TRUE
J 0
(-7050 2500);
DISPLAY 1.170213 (-7050 2500);
PAINT GREEN (-7050 2500);
DISPLAY INVISIBLE (-7050 2500);
FORCEPROP 2 LAST PATH I8
J 0
(-7100 2650);
DISPLAY 1.021277 (-7100 2650);
PAINT ORANGE (-7100 2650);
DISPLAY INVISIBLE (-7100 2650);
FORCEPROP 2 LAST BOM_COST SB
J 0
(-7425 2625);
DISPLAY 1.361702 (-7425 2625);
PAINT ORANGE (-7425 2625);
DISPLAY INVISIBLE (-7425 2625);
FORCEPROP 2 LAST ROOM SB
J 0
(-7425 2625);
DISPLAY 1.361702 (-7425 2625);
PAINT ORANGE (-7425 2625);
DISPLAY INVISIBLE (-7425 2625);
FORCEADD P3V3_STBY..1
(-6325 4575);
FORCEPROP 3 LASTPIN (-6325 4525) SIG_NAME P3V3_STBY\g
J 0
(-6315 4535);
DISPLAY 0.659574 (-6315 4535);
PAINT MONO (-6315 4535);
DISPLAY INVISIBLE (-6315 4535);
FORCEPROP 1 LAST VOLTAGE 3.3V
J 0
(-6370 4532);
DISPLAY 0.340426 (-6370 4532);
PAINT SKYBLUE (-6370 4532);
DISPLAY INVISIBLE (-6370 4532);
FORCEPROP 1 LAST HDL_POWER P3V3_STBY
J 0
(-6625 4450);
DISPLAY 0.872340 (-6625 4450);
PAINT ORANGE (-6625 4450);
DISPLAY INVISIBLE (-6625 4450);
FORCEPROP 2 LAST CDS_LIB mstr_symbols
J 0
(-6325 4575);
PAINT ORANGE (-6325 4575);
DISPLAY INVISIBLE (-6325 4575);
FORCEPROP 1 LAST SIZE 1B
J 0
(-6280 4597);
DISPLAY 0.340426 (-6280 4597);
PAINT GREEN (-6280 4597);
DISPLAY INVISIBLE (-6280 4597);
FORCEPROP 1 LAST BODY_TYPE PLUMBING
J 0
(-6370 4532);
DISPLAY 0.340426 (-6370 4532);
PAINT GREEN (-6370 4532);
DISPLAY INVISIBLE (-6370 4532);
FORCEPROP 1 LAST PATH I9
J 0
(-6280 4577);
DISPLAY 0.340426 (-6280 4577);
PAINT GREEN (-6280 4577);
DISPLAY INVISIBLE (-6280 4577);
FORCEADD DNS..2
(-6195 2345);
PAINT RED (-6195 2345);
FORCEPROP 1 LAST COMMENT_BODY TRUE
R 1
J 0
(-6120 2120);
DISPLAY 0.872340 (-6120 2120);
PAINT GREEN (-6120 2120);
DISPLAY INVISIBLE (-6120 2120);
FORCEPROP 2 LAST CDS_LIB mstr_misc
J 0
(-6195 2345);
PAINT ORANGE (-6195 2345);
DISPLAY INVISIBLE (-6195 2345);
FORCEADD DNS..2
(-4520 2270);
PAINT RED (-4520 2270);
FORCEPROP 1 LAST COMMENT_BODY TRUE
R 1
J 0
(-4445 2045);
DISPLAY 0.872340 (-4445 2045);
PAINT GREEN (-4445 2045);
DISPLAY INVISIBLE (-4445 2045);
FORCEPROP 2 LAST CDS_LIB mstr_misc
J 0
(-4520 2270);
PAINT ORANGE (-4520 2270);
DISPLAY INVISIBLE (-4520 2270);
FORCEADD DESIGN_NOTE..1
(-7675 3875);
FORCEPROP 0 LAST L1 PCH INTERNAL PULL-DOWN, DISABLED AFTER STRAP SAMPLING
J 0
(-7875 3650);
DISPLAY 1.021277 (-7875 3650);
PAINT ORANGE (-7875 3650);
FORCEPROP 0 LAST L3 REAR USB3 PORT ENABLED BY DEFAULT (DCI DISABLED)
J 0
(-7875 3575);
DISPLAY 1.021277 (-7875 3575);
PAINT ORANGE (-7875 3575);
FORCEPROP 0 LAST L2 DCI ENABLED WHEN LOW (DEFAULT), DCI DISABLED WHEN HIGH
J 0
(-7875 3725);
DISPLAY 1.021277 (-7875 3725);
PAINT ORANGE (-7875 3725);
FORCEPROP 0 LAST L4 CHANGE TO 1M FOR DCI FUNCTIONALITY (REAR USB3 DISABLED)
J 0
(-7875 3500);
DISPLAY 1.021277 (-7875 3500);
PAINT ORANGE (-7875 3500);
FORCEPROP 2 LAST ROOM SB_HEADERS
J 0
(-7550 3775);
DISPLAY 1.361702 (-7550 3775);
PAINT ORANGE (-7550 3775);
DISPLAY INVISIBLE (-7550 3775);
FORCEPROP 2 LAST CDS_LIB mstr_symbols
J 0
(-7675 3875);
PAINT ORANGE (-7675 3875);
DISPLAY INVISIBLE (-7675 3875);
FORCEPROP 2 LAST BOM_COST SB
J 0
(-7550 3775);
DISPLAY 1.361702 (-7550 3775);
PAINT ORANGE (-7550 3775);
DISPLAY INVISIBLE (-7550 3775);
FORCEPROP 1 LAST COMMENT_BODY TRUE
J 0
(-7650 3975);
DISPLAY 1.319149 (-7650 3975);
PAINT ORANGE (-7650 3975);
DISPLAY INVISIBLE (-7650 3975);
FORCEADD DNS..2
(-4520 2720);
PAINT RED (-4520 2720);
FORCEPROP 1 LAST COMMENT_BODY TRUE
R 1
J 0
(-4445 2495);
DISPLAY 0.872340 (-4445 2495);
PAINT GREEN (-4445 2495);
DISPLAY INVISIBLE (-4445 2495);
FORCEPROP 2 LAST CDS_LIB mstr_misc
J 0
(-4520 2720);
PAINT ORANGE (-4520 2720);
DISPLAY INVISIBLE (-4520 2720);
FORCEADD DESIGN_NOTE..1
(-7675 2000);
FORCEPROP 0 LAST L2 LT KEY DOWNGRADE DISABLED WHEN HIGH (DEFAULT)
J 0
(-7875 1875);
DISPLAY 1.021277 (-7875 1875);
PAINT ORANGE (-7875 1875);
FORCEPROP 0 LAST L4 NORMAL OC DETECT ENABLE FUNCTIONALITY RESUMES AFTER RSMRST# DEASSERTS
J 0
(-7875 1650);
DISPLAY 1.021277 (-7875 1650);
PAINT ORANGE (-7875 1650);
FORCEPROP 0 LAST L1 PCH INTERNAL PULL-UP
J 0
(-7875 1725);
DISPLAY 1.021277 (-7875 1725);
PAINT ORANGE (-7875 1725);
FORCEPROP 0 LAST L3 LT KEY DOWNGRADE ENABLED WHEN LOW
J 0
(-7875 1800);
DISPLAY 1.021277 (-7875 1800);
PAINT ORANGE (-7875 1800);
FORCEPROP 2 LAST ROOM SB_HEADERS
J 0
(-7550 1900);
DISPLAY 1.361702 (-7550 1900);
PAINT ORANGE (-7550 1900);
DISPLAY INVISIBLE (-7550 1900);
FORCEPROP 2 LAST CDS_LIB mstr_symbols
J 0
(-7675 2000);
PAINT ORANGE (-7675 2000);
DISPLAY INVISIBLE (-7675 2000);
FORCEPROP 2 LAST BOM_COST SB
J 0
(-7550 1900);
DISPLAY 1.361702 (-7550 1900);
PAINT ORANGE (-7550 1900);
DISPLAY INVISIBLE (-7550 1900);
FORCEPROP 1 LAST COMMENT_BODY TRUE
J 0
(-7650 2100);
DISPLAY 1.319149 (-7650 2100);
PAINT ORANGE (-7650 2100);
DISPLAY INVISIBLE (-7650 2100);
FORCEADD DESIGN_NOTE..1
(-4200 2025);
FORCEPROP 0 LAST L4 INTERNAL PULL DOWN DISABLED AFTER RSMRST# DEASSERTS
J 0
(-4375 1675);
DISPLAY 1.021277 (-4375 1675);
PAINT ORANGE (-4375 1675);
FORCEPROP 0 LAST L2 SLAVE ATTACHED FLASH WHEN HIGH
J 0
(-4375 1900);
DISPLAY 1.021277 (-4375 1900);
PAINT ORANGE (-4375 1900);
FORCEPROP 0 LAST L3 MASTER ATTACHED FLASH WHEN LOW (DEFAULT)
J 0
(-4375 1825);
DISPLAY 1.021277 (-4375 1825);
PAINT ORANGE (-4375 1825);
FORCEPROP 0 LAST L1 PCH INTERNAL PULL-DOWN
J 0
(-4375 1750);
DISPLAY 1.021277 (-4375 1750);
PAINT ORANGE (-4375 1750);
FORCEPROP 2 LAST CDS_LIB mstr_symbols
J 0
(-4200 2025);
PAINT ORANGE (-4200 2025);
DISPLAY INVISIBLE (-4200 2025);
FORCEPROP 2 LAST BOM_COST SB
J 0
(-4075 1925);
DISPLAY 1.361702 (-4075 1925);
PAINT ORANGE (-4075 1925);
DISPLAY INVISIBLE (-4075 1925);
FORCEPROP 1 LAST COMMENT_BODY TRUE
J 0
(-4175 2125);
DISPLAY 1.319149 (-4175 2125);
PAINT ORANGE (-4175 2125);
DISPLAY INVISIBLE (-4175 2125);
FORCEPROP 2 LAST ROOM SB_HEADERS
J 0
(-4075 1925);
DISPLAY 1.361702 (-4075 1925);
PAINT ORANGE (-4075 1925);
DISPLAY INVISIBLE (-4075 1925);
FORCEADD DNS..2
(-6320 4295);
PAINT RED (-6320 4295);
FORCEPROP 2 LAST CDS_LIB mstr_misc
J 0
(-6320 4295);
PAINT ORANGE (-6320 4295);
DISPLAY INVISIBLE (-6320 4295);
FORCEPROP 1 LAST COMMENT_BODY TRUE
R 1
J 0
(-6245 4070);
DISPLAY 0.872340 (-6245 4070);
PAINT GREEN (-6245 4070);
DISPLAY INVISIBLE (-6245 4070);
FORCEADD DESIGN_NOTE..1
(-4750 3575);
FORCEPROP 0 LAST L2 ESPI WHEN HIGH
J 0
(-4950 3425);
DISPLAY 1.021277 (-4950 3425);
PAINT ORANGE (-4950 3425);
FORCEPROP 0 LAST L3 LPC WHEN LOW (DEFAULT)
J 0
(-4950 3350);
DISPLAY 1.021277 (-4950 3350);
PAINT ORANGE (-4950 3350);
FORCEPROP 0 LAST L1 PCH INTERNAL PULL-DOWN
J 0
(-4950 3275);
DISPLAY 1.021277 (-4950 3275);
PAINT ORANGE (-4950 3275);
FORCEPROP 0 LAST L4 NORMAL SML ALERT# FUNCTIONALITY RESUMES AFTER RSMRST# DEASSERTS
J 0
(-4950 3200);
DISPLAY 1.021277 (-4950 3200);
PAINT ORANGE (-4950 3200);
FORCEPROP 2 LAST ROOM SB_HEADERS
J 0
(-4625 3475);
DISPLAY 1.361702 (-4625 3475);
PAINT ORANGE (-4625 3475);
DISPLAY INVISIBLE (-4625 3475);
FORCEPROP 2 LAST BOM_COST SB
J 0
(-4625 3475);
DISPLAY 1.361702 (-4625 3475);
PAINT ORANGE (-4625 3475);
DISPLAY INVISIBLE (-4625 3475);
FORCEPROP 2 LAST CDS_LIB mstr_symbols
J 0
(-4750 3575);
PAINT ORANGE (-4750 3575);
DISPLAY INVISIBLE (-4750 3575);
FORCEPROP 1 LAST COMMENT_BODY TRUE
J 0
(-4725 3675);
DISPLAY 1.319149 (-4725 3675);
PAINT ORANGE (-4725 3675);
DISPLAY INVISIBLE (-4725 3675);
FORCEADD INTEL_CORP_BPAGE..1
(0 0);
FORCEPROP 1 LAST CDS_CON_LAST_MODIFIED Fri Jun 16 17:48:49 2017
J 0
(-1425 325);
PAINT ORANGE (-1425 325);
DISPLAY INVISIBLE (-1425 325);
FORCEPROP 1 LAST CUSTOM_TXT_CDS <CURRENT_DESIGN_SHEET> OF <TOTAL_DESIGN_SHEETS>
J 0
(-500 25);
PAINT ORANGE (-500 25);
FORCEPROP 1 LAST CUSTOM_TXT_CDS <CON_LAST_MODIFIED>
J 0
(-4000 100);
PAINT ORANGE (-4000 100);
FORCEPROP 2 LAST CUSTOM_TXT_CDS <XR_PAGE_TITLE>
J 0
(-7890 5250);
DISPLAY 0.638298 (-7890 5250);
PAINT PINK (-7890 5250);
DISPLAY INVISIBLE (-7890 5250);
FORCEPROP 1 LAST SCH_TITLE PCH STRAPS (2/2)
J 0
(-7950 50);
DISPLAY 1.212766 (-7950 50);
PAINT ORANGE (-7950 50);
FORCEPROP 2 LAST PAGE_BORDER TRUE
J 0
(-7890 5250);
DISPLAY 1.021277 (-7890 5250);
PAINT PINK (-7890 5250);
DISPLAY INVISIBLE (-7890 5250);
FORCEPROP 2 LAST CDS_LIB mstr_symbols
J 0
(0 0);
PAINT ORANGE (0 0);
DISPLAY INVISIBLE (0 0);
FORCEPROP 1 LAST COMMENT_BODY TRUE
J 0
(12 12);
DISPLAY 0.510638 (12 12);
PAINT GREEN (12 12);
DISPLAY INVISIBLE (12 12);
FORCEPROP 2 LAST CDS_XR_PAGE_TITLE CR-126 : @BASEBOARD_FAB2_LIB.BASEBOARD_FAB2(SCH_1):PAGE126
J 0
(-7890 5250);
DISPLAY 0.638298 (-7890 5250);
PAINT PINK (-7890 5250);
DISPLAY INVISIBLE (-7890 5250);
WIRE 16 -1 (-3625 3725)(-3625 3625);
WIRE 16 -1 (-3625 4600)(-3625 4525);
WIRE 16 -1 (-4525 2175)(-4525 2100);
WIRE 16 -1 (-4525 2925)(-4525 2825);
WIRE 16 -1 (-6200 2250)(-6200 2150);
WIRE 16 -1 (-6200 2950)(-6200 2875);
WIRE 16 -1 (-6325 4525)(-6325 4400);
WIRE 16 -1 (-7300 4025)(-6325 4025);
FORCEPROP 0 LAST SIG_NAME FM_PCH_BMC_THERMTRIP_EXI_STRAP_N
J 0
(-7285 4035);
DISPLAY 0.617021 (-7285 4035);
PAINT ORANGE (-7285 4035);
WIRE 16 -1 (-6325 4200)(-6325 4025);
WIRE 16 273 (-7900 1625)(-5150 1625);
WIRE 16 273 (-5150 1625)(-5150 3425);
WIRE 16 273 (-1350 3150)(-2275 3150);
WIRE 16 273 (-5100 1625)(-1350 1625);
WIRE 16 273 (-1350 1625)(-1350 3150);
WIRE 16 273 (-7925 3450)(-5150 3450);
WIRE 16 273 (-5150 3450)(-5150 4875);
WIRE 16 273 (-5075 3150)(-2325 3150);
WIRE 16 273 (-2325 3150)(-2325 4950);
WIRE 16 -1 (-7100 2575)(-6200 2575);
FORCEPROP 0 LAST SIG_NAME FM_OC_DETECT_EN_N
J 0
(-7060 2585);
DISPLAY 0.617021 (-7060 2585);
PAINT ORANGE (-7060 2585);
WIRE 16 -1 (-6200 2675)(-6200 2575);
WIRE 16 -1 (-6200 2450)(-6200 2575);
WIRE 16 -1 (-3625 4225)(-3625 4125);
WIRE 16 -1 (-3625 4225)(-2950 4225);
FORCEPROP 2 LAST SIG_NAME IRQ_SML0_ALERT_N
J 0
(-3335 4235);
DISPLAY 0.617021 (-3335 4235);
PAINT ORANGE (-3335 4235);
WIRE 16 -1 (-3625 4325)(-3625 4225);
WIRE 16 -1 (-3825 3825)(-4425 3825);
FORCEPROP 2 LAST SIG_NAME RST_RSMRST_DLY
J 0
(-4385 3835);
DISPLAY 0.617021 (-4385 3835);
PAINT ORANGE (-4385 3835);
WIRE 16 -1 (-4525 2625)(-4525 2475);
WIRE 16 -1 (-4525 2475)(-3425 2475);
FORCEPROP 2 LAST SIG_NAME FM_FLASH_ATTACH_CFG_STRAP
J 0
(-4110 2485);
DISPLAY 0.617021 (-4110 2485);
PAINT ORANGE (-4110 2485);
WIRE 16 -1 (-4525 2375)(-4525 2475);
DOT 1 (-4525 2475);
DOT 1 (-6200 2575);
DOT 1 (-3625 4225);
FORCENOTE
DCI ENABLE
(-7825 4725) 0;
DISPLAY LEFT (-7825 4725);
DISPLAY 2.680851 (-7825 4725);
PAINT PURPLE (-7825 4725);
FORCENOTE
0
(-5650 4300) 0;
DISPLAY LEFT (-5650 4300);
DISPLAY 8.255319 (-5650 4300);
PAINT PURPLE (-5650 4300);
FORCENOTE
TP FAB1 NOPOP R2N10 0108
(-6850 3950) 0;
DISPLAY LEFT (-6850 3950);
DISPLAY 1.021277 (-6850 3950);
PAINT RED (-6850 3950);
FORCENOTE
BIOS FLASH ATTACHMENT
(-4125 2825) 0;
DISPLAY LEFT (-4125 2825);
DISPLAY 2.680851 (-4125 2825);
PAINT PURPLE (-4125 2825);
FORCENOTE
LT KEY DOWNGRADE
(-7775 3175) 0;
DISPLAY LEFT (-7775 3175);
DISPLAY 2.680851 (-7775 3175);
PAINT PURPLE (-7775 3175);
FORCENOTE
CONFIGURATION
(-4125 2675) 0;
DISPLAY LEFT (-4125 2675);
DISPLAY 2.680851 (-4125 2675);
PAINT PURPLE (-4125 2675);
FORCENOTE
ESPI OR LPC
(-5025 4700) 0;
DISPLAY LEFT (-5025 4700);
DISPLAY 2.680851 (-5025 4700);
PAINT PURPLE (-5025 4700);
FORCENOTE
0
(-1975 2625) 0;
DISPLAY LEFT (-1975 2625);
DISPLAY 8.255319 (-1975 2625);
PAINT PURPLE (-1975 2625);
FORCENOTE
0
(-3000 4525) 0;
DISPLAY LEFT (-3000 4525);
DISPLAY 8.255319 (-3000 4525);
PAINT PURPLE (-3000 4525);
FORCENOTE
1
(-5625 2975) 0;
DISPLAY LEFT (-5625 2975);
DISPLAY 8.255319 (-5625 2975);
PAINT PURPLE (-5625 2975);
QUIT
